(kicad_pcb
	(version 20260206)
	(generator "pcbnew")
	(generator_version "10.0")
	(general
		(thickness 1.6)
		(legacy_teardrops no)
	)
	(paper "A4")
	(title_block
		(title "01162023_DA0F0TEBIF0_F0T_Expander_BD_F_brd_V02_OCP.brd")
		(comment 1 "Grand Teton / footprints 6307-6314 of 9728")
	)
	(layers
		(0 "F.Cu" signal "TOP")
		(4 "In1.Cu" signal "GND")
		(6 "In2.Cu" signal "VCC")
		(8 "In3.Cu" signal "VCC1")
		(10 "In4.Cu" signal "GND1")
		(12 "In5.Cu" signal "IN1")
		(14 "In6.Cu" signal "GND2")
		(16 "In7.Cu" signal "IN2")
		(18 "In8.Cu" signal "GND3")
		(20 "In9.Cu" signal "IN3")
		(22 "In10.Cu" signal "GND4")
		(24 "In11.Cu" signal "IN4")
		(26 "In12.Cu" signal "GND5")
		(28 "In13.Cu" signal "IN5")
		(30 "In14.Cu" signal "GND6")
		(32 "In15.Cu" signal "IN6")
		(34 "In16.Cu" signal "GND7")
		(2 "B.Cu" signal "BOTTOM")
		(9 "F.Adhes" user "F.Adhesive")
		(11 "B.Adhes" user "B.Adhesive")
		(13 "F.Paste" user "Package Geometry/Pastemask Top")
		(15 "B.Paste" user "Package Geometry/Pastemask Bottom")
		(5 "F.SilkS" user "Ref Des/Silkscreen Top")
		(7 "B.SilkS" user "Ref Des/Silkscreen Bottom")
		(1 "F.Mask" user "Board Geometry/Soldermask Top")
		(3 "B.Mask" user "Board Geometry/Soldermask Bottom")
		(17 "Dwgs.User" user "User.Drawings")
		(19 "Cmts.User" user "User.Comments")
		(21 "Eco1.User" user "User.Eco1")
		(23 "Eco2.User" user "User.Eco2")
		(25 "Edge.Cuts" user "Board Geometry/Outline")
		(27 "Margin" user)
		(31 "F.CrtYd" user "Package Geometry/Place Bound Top")
		(29 "B.CrtYd" user "Package Geometry/Place Bound Bottom")
		(35 "F.Fab" user "Ref Des/Assembly Top")
		(33 "B.Fab" user "Ref Des/Assembly Bottom")
	)
	(footprint ""
		(layer "F.Cu")
		(at 378.382022 -283.389832 180)
		(property "Reference" "C3584"
			(at 0 0 180)
			(layer "F.SilkS")
			(hide yes)
			(effects
				(font
					(size 1.27 1.27)
				)
			)
		)
		(property "Value" ""
			(at 0 0 180)
			(layer "F.Fab")
			(effects
				(font
					(size 1.27 1.27)
				)
			)
		)
		(duplicate_pad_numbers_are_jumpers no)
		(fp_line
			(start 1.2954 0.5842)
			(end -1.2954 0.5842)
			(stroke
				(width 0.1524)
				(type default)
			)
			(layer "F.SilkS")
		)
		(fp_line
			(start 1.2954 -0.5842)
			(end 1.2954 0.5842)
			(stroke
				(width 0.1524)
				(type default)
			)
			(layer "F.SilkS")
		)
		(fp_line
			(start -1.2954 0.5842)
			(end -1.2954 -0.5842)
			(stroke
				(width 0.1524)
				(type default)
			)
			(layer "F.SilkS")
		)
		(fp_line
			(start -1.2954 -0.5842)
			(end 1.2954 -0.5842)
			(stroke
				(width 0.1524)
				(type default)
			)
			(layer "F.SilkS")
		)
		(fp_line
			(start 1.1938 0.4064)
			(end 0.8636 0.4064)
			(stroke
				(width 0.1)
				(type default)
			)
			(layer "F.Fab")
		)
		(fp_line
			(start 1.1938 -0.4064)
			(end 1.1938 0.4064)
			(stroke
				(width 0.1)
				(type default)
			)
			(layer "F.Fab")
		)
		(fp_line
			(start 0.8636 0.4572)
			(end -0.8636 0.4572)
			(stroke
				(width 0.1)
				(type default)
			)
			(layer "F.Fab")
		)
		(fp_line
			(start 0.8636 0.4064)
			(end 0.8636 0.4572)
			(stroke
				(width 0.1)
				(type default)
			)
			(layer "F.Fab")
		)
		(fp_line
			(start 0.8636 -0.4064)
			(end 1.1938 -0.4064)
			(stroke
				(width 0.1)
				(type default)
			)
			(layer "F.Fab")
		)
		(fp_line
			(start 0.8636 -0.4572)
			(end 0.8636 -0.4064)
			(stroke
				(width 0.1)
				(type default)
			)
			(layer "F.Fab")
		)
		(fp_line
			(start -0.8636 0.4572)
			(end -0.8636 0.4064)
			(stroke
				(width 0.1)
				(type default)
			)
			(layer "F.Fab")
		)
		(fp_line
			(start -0.8636 0.4064)
			(end -1.1938 0.4064)
			(stroke
				(width 0.1)
				(type default)
			)
			(layer "F.Fab")
		)
		(fp_line
			(start -0.8636 -0.4064)
			(end -0.8636 -0.4572)
			(stroke
				(width 0.1)
				(type default)
			)
			(layer "F.Fab")
		)
		(fp_line
			(start -0.8636 -0.4572)
			(end 0.8636 -0.4572)
			(stroke
				(width 0.1)
				(type default)
			)
			(layer "F.Fab")
		)
		(fp_line
			(start -1.1938 0.4064)
			(end -1.1938 -0.4064)
			(stroke
				(width 0.1)
				(type default)
			)
			(layer "F.Fab")
		)
		(fp_line
			(start -1.1938 -0.4064)
			(end -0.8636 -0.4064)
			(stroke
				(width 0.1)
				(type default)
			)
			(layer "F.Fab")
		)
		(pad "1" smd rect
			(at -0.7366 0 90)
			(size 0.7112 0.8128)
			(layers "F.Cu" "F.Mask" "F.Paste")
			(net "PCEPLL7_VDDA18_PEX3_R")
		)
		(pad "2" smd rect
			(at 0.7366 0 90)
			(size 0.7112 0.8128)
			(layers "F.Cu" "F.Mask" "F.Paste")
			(net "GND")
		)
	)
	(footprint ""
		(layer "F.Cu")
		(at 445.022478 -44.341542 90)
		(property "Reference" "R679"
			(at 0 0 90)
			(layer "F.SilkS")
			(hide yes)
			(effects
				(font
					(size 1.27 1.27)
				)
			)
		)
		(property "Value" ""
			(at 0 0 90)
			(layer "F.Fab")
			(effects
				(font
					(size 1.27 1.27)
				)
			)
		)
		(duplicate_pad_numbers_are_jumpers no)
		(fp_line
			(start 0.7874 -0.4064)
			(end 0.7874 0.4064)
			(stroke
				(width 0.1524)
				(type default)
			)
			(layer "F.SilkS")
		)
		(fp_line
			(start -0.7874 -0.4064)
			(end 0.7874 -0.4064)
			(stroke
				(width 0.1524)
				(type default)
			)
			(layer "F.SilkS")
		)
		(fp_line
			(start 0.7874 0.4064)
			(end -0.7874 0.4064)
			(stroke
				(width 0.1524)
				(type default)
			)
			(layer "F.SilkS")
		)
		(fp_line
			(start -0.7874 0.4064)
			(end -0.7874 -0.4064)
			(stroke
				(width 0.1524)
				(type default)
			)
			(layer "F.SilkS")
		)
		(fp_line
			(start -0.12065 -0.305054)
			(end -0.12065 -0.2794)
			(stroke
				(width 0.1)
				(type default)
			)
			(layer "F.Fab")
		)
		(fp_line
			(start -0.67945 -0.305054)
			(end -0.12065 -0.305054)
			(stroke
				(width 0.1)
				(type default)
			)
			(layer "F.Fab")
		)
		(fp_line
			(start 0.67945 -0.3048)
			(end 0.67945 0.3048)
			(stroke
				(width 0.1)
				(type default)
			)
			(layer "F.Fab")
		)
		(fp_line
			(start 0.12065 -0.3048)
			(end 0.67945 -0.3048)
			(stroke
				(width 0.1)
				(type default)
			)
			(layer "F.Fab")
		)
		(fp_line
			(start 0.12065 -0.2794)
			(end 0.12065 -0.3048)
			(stroke
				(width 0.1)
				(type default)
			)
			(layer "F.Fab")
		)
		(fp_line
			(start -0.12065 -0.2794)
			(end 0.12065 -0.2794)
			(stroke
				(width 0.1)
				(type default)
			)
			(layer "F.Fab")
		)
		(fp_line
			(start 0.120396 0.2794)
			(end -0.12065 0.2794)
			(stroke
				(width 0.1)
				(type default)
			)
			(layer "F.Fab")
		)
		(fp_line
			(start -0.12065 0.2794)
			(end -0.12065 0.3048)
			(stroke
				(width 0.1)
				(type default)
			)
			(layer "F.Fab")
		)
		(fp_line
			(start 0.67945 0.3048)
			(end 0.120396 0.3048)
			(stroke
				(width 0.1)
				(type default)
			)
			(layer "F.Fab")
		)
		(fp_line
			(start 0.120396 0.3048)
			(end 0.120396 0.2794)
			(stroke
				(width 0.1)
				(type default)
			)
			(layer "F.Fab")
		)
		(fp_line
			(start -0.12065 0.3048)
			(end -0.67945 0.3048)
			(stroke
				(width 0.1)
				(type default)
			)
			(layer "F.Fab")
		)
		(fp_line
			(start -0.67945 0.3048)
			(end -0.67945 -0.305054)
			(stroke
				(width 0.1)
				(type default)
			)
			(layer "F.Fab")
		)
		(pad "1" smd circle
			(at -0.40005 0 90)
			(size 0 0)
			(layers "F.Cu" "F.Mask" "F.Paste")
			(net "P12V_SSD15")
		)
		(pad "2" smd circle
			(at 0.40005 0 90)
			(size 0 0)
			(layers "F.Cu" "F.Mask" "F.Paste")
			(net "P12V_SSD15_VIN_N")
		)
	)
	(footprint ""
		(layer "F.Cu")
		(at 454.955148 -50.981864 180)
		(property "Reference" "R1755"
			(at 0 0 180)
			(layer "F.SilkS")
			(hide yes)
			(effects
				(font
					(size 1.27 1.27)
				)
			)
		)
		(property "Value" ""
			(at 0 0 180)
			(layer "F.Fab")
			(effects
				(font
					(size 1.27 1.27)
				)
			)
		)
		(duplicate_pad_numbers_are_jumpers no)
		(fp_line
			(start 0.7874 0.4064)
			(end -0.7874 0.4064)
			(stroke
				(width 0.1524)
				(type default)
			)
			(layer "F.SilkS")
		)
		(fp_line
			(start 0.7874 -0.4064)
			(end 0.7874 0.4064)
			(stroke
				(width 0.1524)
				(type default)
			)
			(layer "F.SilkS")
		)
		(fp_line
			(start -0.7874 0.4064)
			(end -0.7874 -0.4064)
			(stroke
				(width 0.1524)
				(type default)
			)
			(layer "F.SilkS")
		)
		(fp_line
			(start -0.7874 -0.4064)
			(end 0.7874 -0.4064)
			(stroke
				(width 0.1524)
				(type default)
			)
			(layer "F.SilkS")
		)
		(fp_line
			(start 0.67945 0.3048)
			(end 0.120396 0.3048)
			(stroke
				(width 0.1)
				(type default)
			)
			(layer "F.Fab")
		)
		(fp_line
			(start 0.67945 -0.3048)
			(end 0.67945 0.3048)
			(stroke
				(width 0.1)
				(type default)
			)
			(layer "F.Fab")
		)
		(fp_line
			(start 0.12065 -0.2794)
			(end 0.12065 -0.3048)
			(stroke
				(width 0.1)
				(type default)
			)
			(layer "F.Fab")
		)
		(fp_line
			(start 0.12065 -0.3048)
			(end 0.67945 -0.3048)
			(stroke
				(width 0.1)
				(type default)
			)
			(layer "F.Fab")
		)
		(fp_line
			(start 0.120396 0.3048)
			(end 0.120396 0.2794)
			(stroke
				(width 0.1)
				(type default)
			)
			(layer "F.Fab")
		)
		(fp_line
			(start 0.120396 0.2794)
			(end -0.12065 0.2794)
			(stroke
				(width 0.1)
				(type default)
			)
			(layer "F.Fab")
		)
		(fp_line
			(start -0.12065 0.3048)
			(end -0.67945 0.3048)
			(stroke
				(width 0.1)
				(type default)
			)
			(layer "F.Fab")
		)
		(fp_line
			(start -0.12065 0.2794)
			(end -0.12065 0.3048)
			(stroke
				(width 0.1)
				(type default)
			)
			(layer "F.Fab")
		)
		(fp_line
			(start -0.12065 -0.2794)
			(end 0.12065 -0.2794)
			(stroke
				(width 0.1)
				(type default)
			)
			(layer "F.Fab")
		)
		(fp_line
			(start -0.12065 -0.305054)
			(end -0.12065 -0.2794)
			(stroke
				(width 0.1)
				(type default)
			)
			(layer "F.Fab")
		)
		(fp_line
			(start -0.67945 0.3048)
			(end -0.67945 -0.305054)
			(stroke
				(width 0.1)
				(type default)
			)
			(layer "F.Fab")
		)
		(fp_line
			(start -0.67945 -0.305054)
			(end -0.12065 -0.305054)
			(stroke
				(width 0.1)
				(type default)
			)
			(layer "F.Fab")
		)
		(pad "1" smd circle
			(at -0.40005 0 180)
			(size 0 0)
			(layers "F.Cu" "F.Mask" "F.Paste")
			(net "P3V3_AUX")
		)
		(pad "2" smd circle
			(at 0.40005 0 180)
			(size 0 0)
			(layers "F.Cu" "F.Mask" "F.Paste")
			(net "SMB_BIC_I2C6_MUX_SSD_8_15_ADC_R_SCL")
		)
	)
	(footprint ""
		(layer "F.Cu")
		(at 464.654646 -526.370296 180)
		(property "Reference" "SCREW_SSD5_2"
			(at -5.207 -1.402334 0)
			(unlocked yes)
			(layer "B.SilkS")
			(effects
				(font
					(size 0.7874 0.5842)
					(thickness 0.1524)
				)
				(justify mirror)
			)
		)
		(property "Value" ""
			(at 0 0 180)
			(layer "F.Fab")
			(effects
				(font
					(size 1.27 1.27)
				)
			)
		)
		(duplicate_pad_numbers_are_jumpers no)
		(pad "1" thru_hole circle
			(at 0 0 180)
			(size 0.4572 0.4572)
			(drill 0.2032)
			(layers "*.Cu" "*.Mask")
			(remove_unused_layers no)
			(net "Net_9133")
			(clearance 0.127)
			(thermal_gap 0.127)
			(padstack
				(mode front_inner_back)
				(layer "Inner"
					(shape circle)
					(size 0.4572 0.4572)
					(clearance 0.127)
				)
				(layer "B.Cu"
					(shape circle)
					(size 0.508 0.508)
					(clearance 0.1016)
				)
			)
		)
	)
	(footprint ""
		(layer "F.Cu")
		(at 344.481404 -343.952322 90)
		(property "Reference" "C580"
			(at 0 0 90)
			(layer "F.SilkS")
			(hide yes)
			(effects
				(font
					(size 1.27 1.27)
				)
			)
		)
		(property "Value" ""
			(at 0 0 90)
			(layer "F.Fab")
			(effects
				(font
					(size 1.27 1.27)
				)
			)
		)
		(duplicate_pad_numbers_are_jumpers no)
		(fp_line
			(start 0.299974 -0.150114)
			(end 0.299974 0.150114)
			(stroke
				(width 0.1)
				(type default)
			)
			(layer "F.Fab")
		)
		(fp_line
			(start -0.299974 -0.150114)
			(end 0.299974 -0.150114)
			(stroke
				(width 0.1)
				(type default)
			)
			(layer "F.Fab")
		)
		(fp_line
			(start 0.299974 0.150114)
			(end -0.299974 0.150114)
			(stroke
				(width 0.1)
				(type default)
			)
			(layer "F.Fab")
		)
		(fp_line
			(start -0.299974 0.150114)
			(end -0.299974 -0.150114)
			(stroke
				(width 0.1)
				(type default)
			)
			(layer "F.Fab")
		)
		(pad "1" smd rect
			(at -0.2667 0 90)
			(size 0.3048 0.381)
			(layers "F.Cu" "F.Mask" "F.Paste")
			(net "P5E_PEX2_STN6_TX_DN<97>")
		)
		(pad "2" smd rect
			(at 0.2667 0 90)
			(size 0.3048 0.381)
			(layers "F.Cu" "F.Mask" "F.Paste")
			(net "P5E_PEX2_STN6_TX_C_DN<97>")
		)
	)
	(footprint ""
		(layer "F.Cu")
		(at 28.823666 -306.366418 45)
		(property "Reference" "R1252"
			(at 0 0 45)
			(layer "F.SilkS")
			(hide yes)
			(effects
				(font
					(size 1.27 1.27)
				)
			)
		)
		(property "Value" ""
			(at 0 0 45)
			(layer "F.Fab")
			(effects
				(font
					(size 1.27 1.27)
				)
			)
		)
		(duplicate_pad_numbers_are_jumpers no)
		(fp_line
			(start -0.787389 -0.406267)
			(end 0.787389 -0.406267)
			(stroke
				(width 0.1524)
				(type default)
			)
			(layer "F.SilkS")
		)
		(fp_line
			(start -0.787389 0.406267)
			(end -0.787389 -0.406267)
			(stroke
				(width 0.1524)
				(type default)
			)
			(layer "F.SilkS")
		)
		(fp_line
			(start 0.787389 -0.406267)
			(end 0.787389 0.406267)
			(stroke
				(width 0.1524)
				(type default)
			)
			(layer "F.SilkS")
		)
		(fp_line
			(start 0.787389 0.406267)
			(end -0.787389 0.406267)
			(stroke
				(width 0.1524)
				(type default)
			)
			(layer "F.SilkS")
		)
		(fp_line
			(start -0.679446 -0.305149)
			(end -0.120695 -0.304969)
			(stroke
				(width 0.1)
				(type default)
			)
			(layer "F.Fab")
		)
		(fp_line
			(start -0.120695 -0.304969)
			(end -0.120695 -0.279466)
			(stroke
				(width 0.1)
				(type default)
			)
			(layer "F.Fab")
		)
		(fp_line
			(start -0.120695 -0.279466)
			(end 0.120695 -0.279466)
			(stroke
				(width 0.1)
				(type default)
			)
			(layer "F.Fab")
		)
		(fp_line
			(start -0.679446 0.30479)
			(end -0.679446 -0.305149)
			(stroke
				(width 0.1)
				(type default)
			)
			(layer "F.Fab")
		)
		(fp_line
			(start 0.120515 -0.30479)
			(end 0.679446 -0.30479)
			(stroke
				(width 0.1)
				(type default)
			)
			(layer "F.Fab")
		)
		(fp_line
			(start 0.120695 -0.279466)
			(end 0.120515 -0.30479)
			(stroke
				(width 0.1)
				(type default)
			)
			(layer "F.Fab")
		)
		(fp_line
			(start -0.120695 0.279466)
			(end -0.120515 0.30479)
			(stroke
				(width 0.1)
				(type default)
			)
			(layer "F.Fab")
		)
		(fp_line
			(start -0.120515 0.30479)
			(end -0.679446 0.30479)
			(stroke
				(width 0.1)
				(type default)
			)
			(layer "F.Fab")
		)
		(fp_line
			(start 0.679446 -0.30479)
			(end 0.679446 0.30479)
			(stroke
				(width 0.1)
				(type default)
			)
			(layer "F.Fab")
		)
		(fp_line
			(start 0.120335 0.279466)
			(end -0.120695 0.279466)
			(stroke
				(width 0.1)
				(type default)
			)
			(layer "F.Fab")
		)
		(fp_line
			(start 0.120515 0.30479)
			(end 0.120335 0.279466)
			(stroke
				(width 0.1)
				(type default)
			)
			(layer "F.Fab")
		)
		(fp_line
			(start 0.679446 0.30479)
			(end 0.120515 0.30479)
			(stroke
				(width 0.1)
				(type default)
			)
			(layer "F.Fab")
		)
		(pad "1" smd circle
			(at -0.40005 0 45)
			(size 0 0)
			(layers "F.Cu" "F.Mask" "F.Paste")
			(net "GND")
		)
		(pad "2" smd circle
			(at 0.40005 0 45)
			(size 0 0)
			(layers "F.Cu" "F.Mask" "F.Paste")
			(net "PEX0_DFT_IDDT")
		)
	)
	(footprint ""
		(layer "F.Cu")
		(at 405.14778 -40.037258 90)
		(property "Reference" "U376"
			(at 0.196342 2.37109 90)
			(unlocked yes)
			(layer "F.SilkS")
			(effects
				(font
					(size 0.7874 0.5842)
					(thickness 0.1524)
				)
			)
		)
		(property "Value" ""
			(at 0 0 90)
			(layer "F.Fab")
			(effects
				(font
					(size 1.27 1.27)
				)
			)
		)
		(duplicate_pad_numbers_are_jumpers no)
		(fp_line
			(start -1.949958 -1.610106)
			(end 1.949958 -1.610106)
			(stroke
				(width 0.1524)
				(type default)
			)
			(layer "F.SilkS")
		)
		(fp_line
			(start 1.949958 -1.560068)
			(end 1.949958 1.610106)
			(stroke
				(width 0.1524)
				(type default)
			)
			(layer "F.SilkS")
		)
		(fp_line
			(start 1.949958 1.610106)
			(end -1.949958 1.610106)
			(stroke
				(width 0.1524)
				(type default)
			)
			(layer "F.SilkS")
		)
		(fp_line
			(start -1.949958 1.610106)
			(end -1.949958 -1.610106)
			(stroke
				(width 0.1524)
				(type default)
			)
			(layer "F.SilkS")
		)
		(fp_line
			(start 0.750062 -1.560068)
			(end 0.750062 1.560068)
			(stroke
				(width 0.1)
				(type default)
			)
			(layer "F.Fab")
		)
		(fp_line
			(start -0.750062 -1.560068)
			(end 0.750062 -1.560068)
			(stroke
				(width 0.1)
				(type default)
			)
			(layer "F.Fab")
		)
		(fp_line
			(start 0.750062 1.560068)
			(end -0.750062 1.560068)
			(stroke
				(width 0.1)
				(type default)
			)
			(layer "F.Fab")
		)
		(fp_line
			(start -0.750062 1.560068)
			(end -0.750062 -1.560068)
			(stroke
				(width 0.1)
				(type default)
			)
			(layer "F.Fab")
		)
		(pad "D" smd rect
			(at 1.100074 0)
			(size 1.016 1.4224)
			(layers "F.Cu" "F.Mask" "F.Paste")
			(net "SSD14_AUX_P3V3_EN")
		)
		(pad "G" smd rect
			(at -1.100074 -0.94996)
			(size 1.016 1.4224)
			(layers "F.Cu" "F.Mask" "F.Paste")
			(net "PRSNT_SSD14_R1_N")
		)
		(pad "S" smd rect
			(at -1.100074 0.94996)
			(size 1.016 1.4224)
			(layers "F.Cu" "F.Mask" "F.Paste")
			(net "GND")
		)
	)
	(footprint ""
		(layer "F.Cu")
		(at 228.305614 -284.252162)
		(property "Reference" "PC239"
			(at 0 0 0)
			(layer "F.SilkS")
			(hide yes)
			(effects
				(font
					(size 1.27 1.27)
				)
			)
		)
		(property "Value" ""
			(at 0 0 0)
			(layer "F.Fab")
			(effects
				(font
					(size 1.27 1.27)
				)
			)
		)
		(duplicate_pad_numbers_are_jumpers no)
		(fp_line
			(start -2.750058 -1.988058)
			(end -2.750058 -0.9398)
			(stroke
				(width 0.1524)
				(type default)
			)
			(layer "F.SilkS")
		)
		(fp_line
			(start -2.750058 0.9398)
			(end -2.750058 1.988058)
			(stroke
				(width 0.1524)
				(type default)
			)
			(layer "F.SilkS")
		)
		(fp_line
			(start -2.750058 1.988058)
			(end -1.988058 2.750058)
			(stroke
				(width 0.1524)
				(type default)
			)
			(layer "F.SilkS")
		)
		(fp_line
			(start -1.988058 -2.750058)
			(end -2.750058 -1.988058)
			(stroke
				(width 0.1524)
				(type default)
			)
			(layer "F.SilkS")
		)
		(fp_line
			(start -1.988058 2.750058)
			(end 2.750058 2.750058)
			(stroke
				(width 0.1524)
				(type default)
			)
			(layer "F.SilkS")
		)
		(fp_line
			(start 2.750058 -2.750058)
			(end -1.988058 -2.750058)
			(stroke
				(width 0.1524)
				(type default)
			)
			(layer "F.SilkS")
		)
		(fp_line
			(start 2.750058 -0.9398)
			(end 2.750058 -2.750058)
			(stroke
				(width 0.1524)
				(type default)
			)
			(layer "F.SilkS")
		)
		(fp_line
			(start 2.750058 2.750058)
			(end 2.750058 0.9398)
			(stroke
				(width 0.1524)
				(type default)
			)
			(layer "F.SilkS")
		)
		(fp_line
			(start -2.750058 -2.750058)
			(end -2.750058 2.750058)
			(stroke
				(width 0.1)
				(type default)
			)
			(layer "F.Fab")
		)
		(fp_line
			(start -2.750058 2.750058)
			(end 2.750058 2.750058)
			(stroke
				(width 0.1)
				(type default)
			)
			(layer "F.Fab")
		)
		(fp_line
			(start 2.750058 -2.750058)
			(end -2.750058 -2.750058)
			(stroke
				(width 0.1)
				(type default)
			)
			(layer "F.Fab")
		)
		(fp_line
			(start 2.750058 2.750058)
			(end 2.750058 -2.750058)
			(stroke
				(width 0.1)
				(type default)
			)
			(layer "F.Fab")
		)
		(pad "1" smd rect
			(at -2.199894 0 90)
			(size 1.6002 3.0226)
			(layers "F.Cu" "F.Mask" "F.Paste")
			(net "P1V25_PEX1_R")
		)
		(pad "2" smd rect
			(at 2.199894 0 90)
			(size 1.6002 3.0226)
			(layers "F.Cu" "F.Mask" "F.Paste")
			(net "GND")
		)
	)
)
